# S9S_MB_2U (Grand Teton) — schematic netlist excerpt (pin names and nets, part order shuffled) for the footprints in the layout excerpt that follows; sources: Cadence DE-HDL packaged netlist, KiCad conversion of 03242023_DA0F0TMBIJ0_F0T_Motherboard_J_brd_V01_OCP.brd

C161  Q_CAP_DIFFBUS  DIFF BUS_0.22UF 6.3V 20% X6S  pkg C0201  page 178 : \1\ = DMI_CPU0_PCH_RX_C_DN<4> ; \2\ = DMI_CPU0_PCH_RX_DN<4>
R693  Q_RES  0 5% CHIP  pkg 0402LF  page 229 : A = I3C_SPD_DDREFGH_CPU0_LVC1_R_SCL ; B = I3C_SPD_DDREFGH_CPU0_LVC1_SCL
R4093  Q_RES  4.7K 1% CHIP  pkg 0402LF  page 171 : A = P3V3_AUX ; B = E1S_0_P3V3_ADC_ALERT_R

(kicad_pcb
	(version 20260206)
	(generator "pcbnew")
	(generator_version "10.0")
	(general
		(thickness 1.6)
		(legacy_teardrops no)
	)
	(paper "A4")
	(title_block
		(title "03242023_DA0F0TMBIJ0_F0T_Motherboard_J_brd_V01_OCP.brd")
		(comment 1 "Grand Teton / footprints 4913-4915 of 6105")
	)
	(layers
		(0 "F.Cu" signal "TOP")
		(4 "In1.Cu" signal "GND")
		(6 "In2.Cu" signal "IN1")
		(8 "In3.Cu" signal "GND1")
		(10 "In4.Cu" signal "IN2")
		(12 "In5.Cu" signal "GND2")
		(14 "In6.Cu" signal "IN3")
		(16 "In7.Cu" signal "GND3")
		(18 "In8.Cu" signal "VCC")
		(20 "In9.Cu" signal "VCC1")
		(22 "In10.Cu" signal "GND4")
		(24 "In11.Cu" signal "IN4")
		(26 "In12.Cu" signal "GND5")
		(28 "In13.Cu" signal "IN5")
		(30 "In14.Cu" signal "GND6")
		(32 "In15.Cu" signal "IN6")
		(34 "In16.Cu" signal "GND7")
		(2 "B.Cu" signal "BOTTOM")
		(9 "F.Adhes" user "F.Adhesive")
		(11 "B.Adhes" user "B.Adhesive")
		(13 "F.Paste" user "Package Geometry/Pastemask Top")
		(15 "B.Paste" user "Package Geometry/Pastemask Bottom")
		(5 "F.SilkS" user "Ref Des/Silkscreen Top")
		(7 "B.SilkS" user "Ref Des/Silkscreen Bottom")
		(1 "F.Mask" user "Board Geometry/Soldermask Top")
		(3 "B.Mask" user "Board Geometry/Soldermask Bottom")
		(17 "Dwgs.User" user "User.Drawings")
		(19 "Cmts.User" user "User.Comments")
		(21 "Eco1.User" user "User.Eco1")
		(23 "Eco2.User" user "User.Eco2")
		(25 "Edge.Cuts" user "Board Geometry/Outline")
		(27 "Margin" user)
		(31 "F.CrtYd" user "Package Geometry/Place Bound Top")
		(29 "B.CrtYd" user "Package Geometry/Place Bound Bottom")
		(35 "F.Fab" user "Ref Des/Assembly Top")
		(33 "B.Fab" user "Ref Des/Assembly Bottom")
	)
	(footprint ""
		(layer "B.Cu")
		(at 212.725 -57.061608 90)
		(property "Reference" "R4093"
			(at 0 0 90)
			(layer "B.SilkS")
			(hide yes)
			(effects
				(font
					(size 1.27 1.27)
				)
				(justify mirror)
			)
		)
		(property "Value" ""
			(at 0 0 90)
			(layer "B.Fab")
			(effects
				(font
					(size 1.27 1.27)
				)
				(justify mirror)
			)
		)
		(duplicate_pad_numbers_are_jumpers no)
		(fp_line
			(start 0.7874 -0.4064)
			(end -0.7874 -0.4064)
			(stroke
				(width 0.1524)
				(type default)
			)
			(layer "B.SilkS")
		)
		(fp_line
			(start -0.7874 -0.4064)
			(end -0.7874 0.4064)
			(stroke
				(width 0.1524)
				(type default)
			)
			(layer "B.SilkS")
		)
		(fp_line
			(start 0.7874 0.4064)
			(end 0.7874 -0.4064)
			(stroke
				(width 0.1524)
				(type default)
			)
			(layer "B.SilkS")
		)
		(fp_line
			(start -0.7874 0.4064)
			(end 0.7874 0.4064)
			(stroke
				(width 0.1524)
				(type default)
			)
			(layer "B.SilkS")
		)
		(fp_line
			(start 0.67945 -0.305054)
			(end 0.12065 -0.305054)
			(stroke
				(width 0.1)
				(type default)
			)
			(layer "B.Fab")
		)
		(fp_line
			(start 0.12065 -0.305054)
			(end 0.12065 -0.2794)
			(stroke
				(width 0.1)
				(type default)
			)
			(layer "B.Fab")
		)
		(fp_line
			(start -0.12065 -0.3048)
			(end -0.67945 -0.3048)
			(stroke
				(width 0.1)
				(type default)
			)
			(layer "B.Fab")
		)
		(fp_line
			(start -0.67945 -0.3048)
			(end -0.67945 0.3048)
			(stroke
				(width 0.1)
				(type default)
			)
			(layer "B.Fab")
		)
		(fp_line
			(start 0.12065 -0.2794)
			(end -0.12065 -0.2794)
			(stroke
				(width 0.1)
				(type default)
			)
			(layer "B.Fab")
		)
		(fp_line
			(start -0.12065 -0.2794)
			(end -0.12065 -0.3048)
			(stroke
				(width 0.1)
				(type default)
			)
			(layer "B.Fab")
		)
		(fp_line
			(start 0.12065 0.2794)
			(end 0.12065 0.3048)
			(stroke
				(width 0.1)
				(type default)
			)
			(layer "B.Fab")
		)
		(fp_line
			(start -0.120396 0.2794)
			(end 0.12065 0.2794)
			(stroke
				(width 0.1)
				(type default)
			)
			(layer "B.Fab")
		)
		(fp_line
			(start 0.67945 0.3048)
			(end 0.67945 -0.305054)
			(stroke
				(width 0.1)
				(type default)
			)
			(layer "B.Fab")
		)
		(fp_line
			(start 0.12065 0.3048)
			(end 0.67945 0.3048)
			(stroke
				(width 0.1)
				(type default)
			)
			(layer "B.Fab")
		)
		(fp_line
			(start -0.120396 0.3048)
			(end -0.120396 0.2794)
			(stroke
				(width 0.1)
				(type default)
			)
			(layer "B.Fab")
		)
		(fp_line
			(start -0.67945 0.3048)
			(end -0.120396 0.3048)
			(stroke
				(width 0.1)
				(type default)
			)
			(layer "B.Fab")
		)
		(pad "1" smd circle
			(at 0.40005 0 270)
			(size 0 0)
			(layers "B.Cu" "B.Mask" "B.Paste")
			(net "P3V3_AUX")
		)
		(pad "2" smd circle
			(at -0.40005 0 270)
			(size 0 0)
			(layers "B.Cu" "B.Mask" "B.Paste")
			(net "E1S_0_P3V3_ADC_ALERT_R")
		)
	)
	(footprint ""
		(layer "B.Cu")
		(at 305.624738 -153.82367 180)
		(property "Reference" "R693"
			(at 0 0 0)
			(layer "B.SilkS")
			(hide yes)
			(effects
				(font
					(size 1.27 1.27)
				)
				(justify mirror)
			)
		)
		(property "Value" ""
			(at 0 0 0)
			(layer "B.Fab")
			(effects
				(font
					(size 1.27 1.27)
				)
				(justify mirror)
			)
		)
		(duplicate_pad_numbers_are_jumpers no)
		(fp_line
			(start 0.7874 0.4064)
			(end 0.7874 -0.4064)
			(stroke
				(width 0.1524)
				(type default)
			)
			(layer "B.SilkS")
		)
		(fp_line
			(start 0.7874 -0.4064)
			(end -0.7874 -0.4064)
			(stroke
				(width 0.1524)
				(type default)
			)
			(layer "B.SilkS")
		)
		(fp_line
			(start -0.7874 0.4064)
			(end 0.7874 0.4064)
			(stroke
				(width 0.1524)
				(type default)
			)
			(layer "B.SilkS")
		)
		(fp_line
			(start -0.7874 -0.4064)
			(end -0.7874 0.4064)
			(stroke
				(width 0.1524)
				(type default)
			)
			(layer "B.SilkS")
		)
		(fp_line
			(start 0.67945 0.3048)
			(end 0.67945 -0.305054)
			(stroke
				(width 0.1)
				(type default)
			)
			(layer "B.Fab")
		)
		(fp_line
			(start 0.67945 -0.305054)
			(end 0.12065 -0.305054)
			(stroke
				(width 0.1)
				(type default)
			)
			(layer "B.Fab")
		)
		(fp_line
			(start 0.12065 0.3048)
			(end 0.67945 0.3048)
			(stroke
				(width 0.1)
				(type default)
			)
			(layer "B.Fab")
		)
		(fp_line
			(start 0.12065 0.2794)
			(end 0.12065 0.3048)
			(stroke
				(width 0.1)
				(type default)
			)
			(layer "B.Fab")
		)
		(fp_line
			(start 0.12065 -0.2794)
			(end -0.12065 -0.2794)
			(stroke
				(width 0.1)
				(type default)
			)
			(layer "B.Fab")
		)
		(fp_line
			(start 0.12065 -0.305054)
			(end 0.12065 -0.2794)
			(stroke
				(width 0.1)
				(type default)
			)
			(layer "B.Fab")
		)
		(fp_line
			(start -0.120396 0.3048)
			(end -0.120396 0.2794)
			(stroke
				(width 0.1)
				(type default)
			)
			(layer "B.Fab")
		)
		(fp_line
			(start -0.120396 0.2794)
			(end 0.12065 0.2794)
			(stroke
				(width 0.1)
				(type default)
			)
			(layer "B.Fab")
		)
		(fp_line
			(start -0.12065 -0.2794)
			(end -0.12065 -0.3048)
			(stroke
				(width 0.1)
				(type default)
			)
			(layer "B.Fab")
		)
		(fp_line
			(start -0.12065 -0.3048)
			(end -0.67945 -0.3048)
			(stroke
				(width 0.1)
				(type default)
			)
			(layer "B.Fab")
		)
		(fp_line
			(start -0.67945 0.3048)
			(end -0.120396 0.3048)
			(stroke
				(width 0.1)
				(type default)
			)
			(layer "B.Fab")
		)
		(fp_line
			(start -0.67945 -0.3048)
			(end -0.67945 0.3048)
			(stroke
				(width 0.1)
				(type default)
			)
			(layer "B.Fab")
		)
		(pad "1" smd circle
			(at 0.40005 0)
			(size 0 0)
			(layers "B.Cu" "B.Mask" "B.Paste")
			(net "I3C_SPD_DDREFGH_CPU0_LVC1_R_SCL")
		)
		(pad "2" smd circle
			(at -0.40005 0)
			(size 0 0)
			(layers "B.Cu" "B.Mask" "B.Paste")
			(net "I3C_SPD_DDREFGH_CPU0_LVC1_SCL")
		)
	)
	(footprint ""
		(layer "B.Cu")
		(at 344.754708 -62.056264 90)
		(property "Reference" "C161"
			(at 0 0 90)
			(layer "B.SilkS")
			(hide yes)
			(effects
				(font
					(size 1.27 1.27)
				)
				(justify mirror)
			)
		)
		(property "Value" ""
			(at 0 0 90)
			(layer "B.Fab")
			(effects
				(font
					(size 1.27 1.27)
				)
				(justify mirror)
			)
		)
		(duplicate_pad_numbers_are_jumpers no)
		(fp_line
			(start 0.299974 -0.150114)
			(end -0.299974 -0.150114)
			(stroke
				(width 0.1)
				(type default)
			)
			(layer "B.Fab")
		)
		(fp_line
			(start -0.299974 -0.150114)
			(end -0.299974 0.150114)
			(stroke
				(width 0.1)
				(type default)
			)
			(layer "B.Fab")
		)
		(fp_line
			(start 0.299974 0.150114)
			(end 0.299974 -0.150114)
			(stroke
				(width 0.1)
				(type default)
			)
			(layer "B.Fab")
		)
		(fp_line
			(start -0.299974 0.150114)
			(end 0.299974 0.150114)
			(stroke
				(width 0.1)
				(type default)
			)
			(layer "B.Fab")
		)
		(pad "1" smd rect
			(at 0.2667 0 270)
			(size 0.3048 0.381)
			(layers "B.Cu" "B.Mask" "B.Paste")
			(net "DMI_CPU0_PCH_RX_C_DN<4>")
		)
		(pad "2" smd rect
			(at -0.2667 0 270)
			(size 0.3048 0.381)
			(layers "B.Cu" "B.Mask" "B.Paste")
			(net "DMI_CPU0_PCH_RX_DN<4>")
		)
	)
)
